#ISCELL
  mstr_misc dns *
  *
#ISCELL
  pure_quanta quanta_title_block_c *
  *
#ISCELL
  pure_quanta_power universal_gnd *
  page181_i1
#CELL
  pure_quanta q_cap *
  page181_i100
#CELL
  pure_quanta q_cap *
  page181_i101
#CELL
  pure_quanta q_cap *
  page181_i102
#ISCELL
  pure_quanta_power universal_gnd *
  page181_i103
#ISCELL
  pure_quanta_power universal_gnd *
  page181_i104
#CELL
  pure_quanta q_res *
  page181_i105
#CELL
  pure_quanta q_cap *
  page181_i106
#CELL
  pure_quanta q_cap *
  page181_i108
#ISCELL
  pure_quanta_power universal_gnd *
  page181_i109
#ISCELL
  pure_quanta_power universal_gnd *
  page181_i110
#CELL
  pure_quanta q_res *
  page181_i111
#CELL
  pure_quanta q_cap *
  page181_i112
#ISCELL
  pure_quanta_power universal_gnd *
  page181_i114
#ISCELL
  pure_quanta_power universal_gnd *
  page181_i115
#ISCELL
  pure_quanta_power universal_gnd *
  page181_i117
#CELL
  pure_quanta q_res *
  page181_i118
#CELL
  pure_quanta q_cap *
  page181_i119
#ISCELL
  pure_quanta_power universal_gnd *
  page181_i120
#CELL
  pure_quanta q_res *
  page181_i121
#CELL
  pure_quanta q_cap *
  page181_i122
#ISCELL
  pure_quanta_power vcc_core *
  page181_i123
#ISCELL
  pure_quanta_power vcc_core *
  page181_i124
#CELL
  pure_quanta q_inductor *
  page181_i125
#ISCELL
  pure_quanta_power universal_gnd *
  page181_i126
#ISCELL
  standard offpage *
  page181_i127
#ISCELL
  pure_quanta_power universal_gnd *
  page181_i14
#CELL
  pure_quanta q_res *
  page181_i15
#CELL
  pure_quanta q_res *
  page181_i2
#ISCELL
  standard offpage *
  page181_i21
#ISCELL
  standard offpage *
  page181_i22
#CELL
  pure_quanta isl99390frztr5935 *
  page181_i23
#ISCELL
  pure_quanta_power universal_gnd *
  page181_i24
#CELL
  pure_quanta isl99390frztr5935 *
  page181_i26
#CELL
  pure_quanta q_cap *
  page181_i28
#ISCELL
  pure_quanta_power universal_gnd *
  page181_i29
#ISCELL
  standard offpage *
  page181_i33
#ISCELL
  standard offpage *
  page181_i34
#ISCELL
  standard offpage *
  page181_i4
#CELL
  pure_quanta q_cap *
  page181_i44
#CELL
  pure_quanta q_inductor4p_14 *
  page181_i46
#ISCELL
  pure_quanta_power universal_gnd *
  page181_i49
#ISCELL
  standard offpage *
  page181_i5
#CELL
  pure_quanta q_cap *
  page181_i51
#CELL
  pure_quanta q_cap *
  page181_i52
#CELL
  pure_quanta q_cap *
  page181_i55
#CELL
  pure_quanta q_res *
  page181_i57
#CELL
  pure_quanta q_cap *
  page181_i59
#ISCELL
  standard offpage *
  page181_i6
#ISCELL
  standard offpage *
  page181_i61
#CELL
  pure_quanta q_cap *
  page181_i65
#CELL
  pure_quanta q_cap *
  page181_i67
#CELL
  pure_quanta q_cap *
  page181_i68
#CELL
  pure_quanta q_cap *
  page181_i69
#ISCELL
  standard offpage *
  page181_i7
#ISCELL
  pure_quanta_power universal_gnd *
  page181_i70
#CELL
  pure_quanta q_cap *
  page181_i71
#ISCELL
  pure_quanta_power vcc_core *
  page181_i72
#ISCELL
  pure_quanta_power universal_gnd *
  page181_i77
#CELL
  pure_quanta q_cap *
  page181_i78
#ISCELL
  pure_quanta_power vcc_core *
  page181_i79
#CELL
  pure_quanta q_cap *
  page181_i8
#CELL
  pure_quanta q_cap *
  page181_i84
#ISCELL
  pure_quanta_power universal_gnd *
  page181_i85
#ISCELL
  pure_quanta_power vcc_core *
  page181_i86
#ISCELL
  pure_quanta_power vcc_core *
  page181_i87
#ISCELL
  standard offpage *
  page181_i89
#CELL
  pure_quanta q_inductor4p_14 *
  page181_i93
#CELL
  pure_quanta q_cap *
  page181_i94
#CELL
  pure_quanta q_res *
  page181_i95
#CELL
  pure_quanta q_cap *
  page181_i97
#CELL
  pure_quanta q_res *
  page181_i98
#CELL
  pure_quanta q_res *
  page181_i99
